#ISCELL
  cls sheet_a1 *
  *
#ISCELL
  cls offpage_out *
  page11_i1
#ISCELL
  cls offpage_out *
  page11_i10
#CELL
  passive resistor *
  page11_i11
#CELL
  passive capacitor *
  page11_i12
#CELL
  passive capacitor *
  page11_i13
#ISCELL
  cls gnd_sg *
  page11_i14
#CELL
  passive capacitor *
  page11_i15
#ISCELL
  cls vcc *
  page11_i16
#ISCELL
  cls gnd_sg *
  page11_i17
#CELL
  passive resistor *
  page11_i18
#ISCELL
  cls offpage_out *
  page11_i19
#CELL
  passive resistor *
  page11_i20
#CELL
  passive resistor *
  page11_i21
#ISCELL
  cls gnd_sg *
  page11_i22
#CELL
  passive capacitor *
  page11_i24
#CELL
  passive resistor *
  page11_i25
#CELL
  passive capacitor *
  page11_i26
#ISCELL
  cls offpage_in *
  page11_i28
#CELL
  passive resistor *
  page11_i29
#ISCELL
  cls vcc *
  page11_i32
#CELL
  connector conn_hdr_2x4_f_s_smt *
  page11_i36
#CELL
  passive resistor *
  page11_i38
#ISCELL
  cls vcc *
  page11_i39
#CELL
  passive resistor *
  page11_i40
#ISCELL
  cls vcc *
  page11_i42
#CELL
  passive capacitor *
  page11_i43
#CELL
  passive capacitor *
  page11_i44
#CELL
  passive capacitor *
  page11_i45
#ISCELL
  cls offpage_out *
  page11_i46
#ISCELL
  cls offpage_in *
  page11_i47
#CELL
  passive resistor *
  page11_i5
#ISCELL
  cls vcc *
  page11_i54
#CELL
  passive ferritebead *
  page11_i55
#CELL
  passive ferritebead *
  page11_i56
#ISCELL
  cls offpage_in *
  page11_i57
#CELL
  passive resistor *
  page11_i7
#CELL
  passive resistor *
  page11_i8
#ISCELL
  cls offpage_in *
  page11_i9
